# T6G (Grand Teton) — schematic netlist excerpt (pin names and nets, part order shuffled) for the footprints in the layout excerpt that follows; sources: Cadence DE-HDL packaged netlist, KiCad conversion of 04192023_DAF0TMB3IC0_F0TG_MB_C_brd_V02_OCP.brd

R1050  Q_RES  0 5% EMPTY  pkg 0402LF  page 301 : A = P1V8_CPU0_RT_1D ; B = P1V8_CPU0_RT2_1A_1D
PR369  Q_RES  8.87K 1% EMPTY  pkg 0402LF  page 223 : A = PVDDIO_P1_LSET3 ; B = GND

(kicad_pcb
	(version 20260206)
	(generator "pcbnew")
	(generator_version "10.0")
	(general
		(thickness 1.6)
		(legacy_teardrops no)
	)
	(paper "A4")
	(title_block
		(title "04192023_DAF0TMB3IC0_F0TG_MB_C_brd_V02_OCP.brd")
		(comment 1 "Grand Teton / footprints 2982-2983 of 8354")
	)
	(layers
		(0 "F.Cu" signal "TOP")
		(4 "In1.Cu" signal "GND")
		(6 "In2.Cu" signal "IN1")
		(8 "In3.Cu" signal "GND1")
		(10 "In4.Cu" signal "IN2")
		(12 "In5.Cu" signal "GND2")
		(14 "In6.Cu" signal "IN3")
		(16 "In7.Cu" signal "GND3")
		(18 "In8.Cu" signal "VCC")
		(20 "In9.Cu" signal "VCC1")
		(22 "In10.Cu" signal "GND4")
		(24 "In11.Cu" signal "IN4")
		(26 "In12.Cu" signal "GND5")
		(28 "In13.Cu" signal "IN5")
		(30 "In14.Cu" signal "GND6")
		(32 "In15.Cu" signal "IN6")
		(34 "In16.Cu" signal "GND7")
		(2 "B.Cu" signal "BOTTOM")
		(9 "F.Adhes" user "F.Adhesive")
		(11 "B.Adhes" user "B.Adhesive")
		(13 "F.Paste" user "Package Geometry/Pastemask Top")
		(15 "B.Paste" user "Package Geometry/Pastemask Bottom")
		(5 "F.SilkS" user "Ref Des/Silkscreen Top")
		(7 "B.SilkS" user "Ref Des/Silkscreen Bottom")
		(1 "F.Mask" user "Board Geometry/Soldermask Top")
		(3 "B.Mask" user "Board Geometry/Soldermask Bottom")
		(17 "Dwgs.User" user "User.Drawings")
		(19 "Cmts.User" user "User.Comments")
		(21 "Eco1.User" user "User.Eco1")
		(23 "Eco2.User" user "User.Eco2")
		(25 "Edge.Cuts" user "Board Geometry/Outline")
		(27 "Margin" user)
		(31 "F.CrtYd" user "Package Geometry/Place Bound Top")
		(29 "B.CrtYd" user "Package Geometry/Place Bound Bottom")
		(35 "F.Fab" user "Ref Des/Assembly Top")
		(33 "B.Fab" user "Ref Des/Assembly Bottom")
	)
	(footprint ""
		(layer "F.Cu")
		(at 427.269656 -396.145004 180)
		(property "Reference" "R1050"
			(at 0 0 180)
			(layer "F.SilkS")
			(hide yes)
			(effects
				(font
					(size 1.27 1.27)
				)
			)
		)
		(property "Value" ""
			(at 0 0 180)
			(layer "F.Fab")
			(effects
				(font
					(size 1.27 1.27)
				)
			)
		)
		(duplicate_pad_numbers_are_jumpers no)
		(fp_line
			(start 0.7874 0.4064)
			(end -0.7874 0.4064)
			(stroke
				(width 0.1524)
				(type default)
			)
			(layer "F.SilkS")
		)
		(fp_line
			(start 0.7874 -0.4064)
			(end 0.7874 0.4064)
			(stroke
				(width 0.1524)
				(type default)
			)
			(layer "F.SilkS")
		)
		(fp_line
			(start -0.7874 0.4064)
			(end -0.7874 -0.4064)
			(stroke
				(width 0.1524)
				(type default)
			)
			(layer "F.SilkS")
		)
		(fp_line
			(start -0.7874 -0.4064)
			(end 0.7874 -0.4064)
			(stroke
				(width 0.1524)
				(type default)
			)
			(layer "F.SilkS")
		)
		(fp_line
			(start 0.67945 0.3048)
			(end 0.120396 0.3048)
			(stroke
				(width 0.1)
				(type default)
			)
			(layer "F.Fab")
		)
		(fp_line
			(start 0.67945 -0.3048)
			(end 0.67945 0.3048)
			(stroke
				(width 0.1)
				(type default)
			)
			(layer "F.Fab")
		)
		(fp_line
			(start 0.12065 -0.2794)
			(end 0.12065 -0.3048)
			(stroke
				(width 0.1)
				(type default)
			)
			(layer "F.Fab")
		)
		(fp_line
			(start 0.12065 -0.3048)
			(end 0.67945 -0.3048)
			(stroke
				(width 0.1)
				(type default)
			)
			(layer "F.Fab")
		)
		(fp_line
			(start 0.120396 0.3048)
			(end 0.120396 0.2794)
			(stroke
				(width 0.1)
				(type default)
			)
			(layer "F.Fab")
		)
		(fp_line
			(start 0.120396 0.2794)
			(end -0.12065 0.2794)
			(stroke
				(width 0.1)
				(type default)
			)
			(layer "F.Fab")
		)
		(fp_line
			(start -0.12065 0.3048)
			(end -0.67945 0.3048)
			(stroke
				(width 0.1)
				(type default)
			)
			(layer "F.Fab")
		)
		(fp_line
			(start -0.12065 0.2794)
			(end -0.12065 0.3048)
			(stroke
				(width 0.1)
				(type default)
			)
			(layer "F.Fab")
		)
		(fp_line
			(start -0.12065 -0.2794)
			(end 0.12065 -0.2794)
			(stroke
				(width 0.1)
				(type default)
			)
			(layer "F.Fab")
		)
		(fp_line
			(start -0.12065 -0.305054)
			(end -0.12065 -0.2794)
			(stroke
				(width 0.1)
				(type default)
			)
			(layer "F.Fab")
		)
		(fp_line
			(start -0.67945 0.3048)
			(end -0.67945 -0.305054)
			(stroke
				(width 0.1)
				(type default)
			)
			(layer "F.Fab")
		)
		(fp_line
			(start -0.67945 -0.305054)
			(end -0.12065 -0.305054)
			(stroke
				(width 0.1)
				(type default)
			)
			(layer "F.Fab")
		)
		(pad "1" smd rect
			(at -0.40005 0)
			(size 0.4572 0.508)
			(layers "F.Cu" "F.Mask" "F.Paste")
			(net "P1V8_CPU0_RT_1D")
		)
		(pad "2" smd rect
			(at 0.40005 0)
			(size 0.4572 0.508)
			(layers "F.Cu" "F.Mask" "F.Paste")
			(net "P1V8_CPU0_RT2_1A_1D")
		)
	)
	(footprint ""
		(layer "F.Cu")
		(at 35.57651 -351.932748)
		(property "Reference" "PR369"
			(at 0 0 0)
			(layer "F.SilkS")
			(hide yes)
			(effects
				(font
					(size 1.27 1.27)
				)
			)
		)
		(property "Value" ""
			(at 0 0 0)
			(layer "F.Fab")
			(effects
				(font
					(size 1.27 1.27)
				)
			)
		)
		(duplicate_pad_numbers_are_jumpers no)
		(fp_line
			(start -0.7874 -0.4064)
			(end 0.7874 -0.4064)
			(stroke
				(width 0.1524)
				(type default)
			)
			(layer "F.SilkS")
		)
		(fp_line
			(start -0.7874 0.4064)
			(end -0.7874 -0.4064)
			(stroke
				(width 0.1524)
				(type default)
			)
			(layer "F.SilkS")
		)
		(fp_line
			(start 0.7874 -0.4064)
			(end 0.7874 0.4064)
			(stroke
				(width 0.1524)
				(type default)
			)
			(layer "F.SilkS")
		)
		(fp_line
			(start 0.7874 0.4064)
			(end -0.7874 0.4064)
			(stroke
				(width 0.1524)
				(type default)
			)
			(layer "F.SilkS")
		)
		(fp_line
			(start -0.67945 -0.305054)
			(end -0.12065 -0.305054)
			(stroke
				(width 0.1)
				(type default)
			)
			(layer "F.Fab")
		)
		(fp_line
			(start -0.67945 0.3048)
			(end -0.67945 -0.305054)
			(stroke
				(width 0.1)
				(type default)
			)
			(layer "F.Fab")
		)
		(fp_line
			(start -0.12065 -0.305054)
			(end -0.12065 -0.2794)
			(stroke
				(width 0.1)
				(type default)
			)
			(layer "F.Fab")
		)
		(fp_line
			(start -0.12065 -0.2794)
			(end 0.12065 -0.2794)
			(stroke
				(width 0.1)
				(type default)
			)
			(layer "F.Fab")
		)
		(fp_line
			(start -0.12065 0.2794)
			(end -0.12065 0.3048)
			(stroke
				(width 0.1)
				(type default)
			)
			(layer "F.Fab")
		)
		(fp_line
			(start -0.12065 0.3048)
			(end -0.67945 0.3048)
			(stroke
				(width 0.1)
				(type default)
			)
			(layer "F.Fab")
		)
		(fp_line
			(start 0.120396 0.2794)
			(end -0.12065 0.2794)
			(stroke
				(width 0.1)
				(type default)
			)
			(layer "F.Fab")
		)
		(fp_line
			(start 0.120396 0.3048)
			(end 0.120396 0.2794)
			(stroke
				(width 0.1)
				(type default)
			)
			(layer "F.Fab")
		)
		(fp_line
			(start 0.12065 -0.3048)
			(end 0.67945 -0.3048)
			(stroke
				(width 0.1)
				(type default)
			)
			(layer "F.Fab")
		)
		(fp_line
			(start 0.12065 -0.2794)
			(end 0.12065 -0.3048)
			(stroke
				(width 0.1)
				(type default)
			)
			(layer "F.Fab")
		)
		(fp_line
			(start 0.67945 -0.3048)
			(end 0.67945 0.3048)
			(stroke
				(width 0.1)
				(type default)
			)
			(layer "F.Fab")
		)
		(fp_line
			(start 0.67945 0.3048)
			(end 0.120396 0.3048)
			(stroke
				(width 0.1)
				(type default)
			)
			(layer "F.Fab")
		)
		(pad "1" smd circle
			(at -0.40005 0)
			(size 0 0)
			(layers "F.Cu" "F.Mask" "F.Paste")
			(net "PVDDIO_P1_LSET3")
		)
		(pad "2" smd circle
			(at 0.40005 0)
			(size 0 0)
			(layers "F.Cu" "F.Mask" "F.Paste")
			(net "GND")
		)
	)
)
